# S9S_MB_2U (Grand Teton) — schematic netlist excerpt (pin names and nets, part order shuffled) for the footprints in the layout excerpt that follows; sources: Cadence DE-HDL packaged netlist, KiCad conversion of 03242023_DA0F0TMBIJ0_F0T_Motherboard_J_brd_V01_OCP.brd

PC2362  Q_CAP  0.1UF 25V 10% EMPTY  pkg 0402  page 274 : A = PVCCINFAON_CPU0_VCC ; B = GND
PC720_P0_1  Q_CAP  22UF 16V 20% X6S  pkg C0805  page 271 : A = SW_P12V_PVCCFA_EHV_FIVRA_CPU0_R ; B = GND

Q145  MOSFET_NCH_DUAL  PJT138K IC  pkg SOT363XD  page 246
  S1  = GND
  G1  = HPDB_HSC_PWRGD
  D2  = HPDB_HSC_PWRGD_ISO
  S2  = GND
  G2  = HPDB_HSC_PWRGD_N
  D1  = HPDB_HSC_PWRGD_N

(kicad_pcb
	(version 20260206)
	(generator "pcbnew")
	(generator_version "10.0")
	(general
		(thickness 1.6)
		(legacy_teardrops no)
	)
	(paper "A4")
	(title_block
		(title "03242023_DA0F0TMBIJ0_F0T_Motherboard_J_brd_V01_OCP.brd")
		(comment 1 "Grand Teton / footprints 432-434 of 6105")
	)
	(layers
		(0 "F.Cu" signal "TOP")
		(4 "In1.Cu" signal "GND")
		(6 "In2.Cu" signal "IN1")
		(8 "In3.Cu" signal "GND1")
		(10 "In4.Cu" signal "IN2")
		(12 "In5.Cu" signal "GND2")
		(14 "In6.Cu" signal "IN3")
		(16 "In7.Cu" signal "GND3")
		(18 "In8.Cu" signal "VCC")
		(20 "In9.Cu" signal "VCC1")
		(22 "In10.Cu" signal "GND4")
		(24 "In11.Cu" signal "IN4")
		(26 "In12.Cu" signal "GND5")
		(28 "In13.Cu" signal "IN5")
		(30 "In14.Cu" signal "GND6")
		(32 "In15.Cu" signal "IN6")
		(34 "In16.Cu" signal "GND7")
		(2 "B.Cu" signal "BOTTOM")
		(9 "F.Adhes" user "F.Adhesive")
		(11 "B.Adhes" user "B.Adhesive")
		(13 "F.Paste" user "Package Geometry/Pastemask Top")
		(15 "B.Paste" user "Package Geometry/Pastemask Bottom")
		(5 "F.SilkS" user "Ref Des/Silkscreen Top")
		(7 "B.SilkS" user "Ref Des/Silkscreen Bottom")
		(1 "F.Mask" user "Board Geometry/Soldermask Top")
		(3 "B.Mask" user "Board Geometry/Soldermask Bottom")
		(17 "Dwgs.User" user "User.Drawings")
		(19 "Cmts.User" user "User.Comments")
		(21 "Eco1.User" user "User.Eco1")
		(23 "Eco2.User" user "User.Eco2")
		(25 "Edge.Cuts" user "Board Geometry/Outline")
		(27 "Margin" user)
		(31 "F.CrtYd" user "Package Geometry/Place Bound Top")
		(29 "B.CrtYd" user "Package Geometry/Place Bound Bottom")
		(35 "F.Fab" user "Ref Des/Assembly Top")
		(33 "B.Fab" user "Ref Des/Assembly Bottom")
	)
	(footprint ""
		(layer "F.Cu")
		(at 289.116008 -412.34614)
		(property "Reference" "Q145"
			(at -1.438148 1.759204 0)
			(unlocked yes)
			(layer "F.SilkS")
			(effects
				(font
					(size 0.7874 0.5842)
					(thickness 0.1524)
				)
				(justify left)
			)
		)
		(property "Value" ""
			(at 0 0 0)
			(layer "F.Fab")
			(effects
				(font
					(size 1.27 1.27)
				)
			)
		)
		(duplicate_pad_numbers_are_jumpers no)
		(fp_line
			(start -1.332738 -1.100074)
			(end -0.4826 -1.100074)
			(stroke
				(width 0.1524)
				(type default)
			)
			(layer "F.SilkS")
		)
		(fp_line
			(start -1.332738 1.100074)
			(end -1.332738 -1.100074)
			(stroke
				(width 0.1524)
				(type default)
			)
			(layer "F.SilkS")
		)
		(fp_line
			(start -0.4826 -1.100074)
			(end 0 -0.541274)
			(stroke
				(width 0.1524)
				(type default)
			)
			(layer "F.SilkS")
		)
		(fp_line
			(start 0 -0.541274)
			(end 0.4826 -1.100074)
			(stroke
				(width 0.1524)
				(type default)
			)
			(layer "F.SilkS")
		)
		(fp_line
			(start 0.4826 -1.100074)
			(end 1.332738 -1.100074)
			(stroke
				(width 0.1524)
				(type default)
			)
			(layer "F.SilkS")
		)
		(fp_line
			(start 1.332738 -1.100074)
			(end 1.332738 1.100074)
			(stroke
				(width 0.1524)
				(type default)
			)
			(layer "F.SilkS")
		)
		(fp_line
			(start 1.332738 1.100074)
			(end -1.332738 1.100074)
			(stroke
				(width 0.1524)
				(type default)
			)
			(layer "F.SilkS")
		)
		(fp_poly
			(pts
				(xy -1.756156 -1.726946) (xy -1.507998 -0.982218) (xy -2.252726 -1.230376)
			)
			(stroke
				(width 0)
				(type default)
			)
			(fill yes)
			(layer "F.SilkS")
		)
		(fp_line
			(start -0.674878 -1.100074)
			(end 0.674878 -1.100074)
			(stroke
				(width 0.1)
				(type default)
			)
			(layer "F.Fab")
		)
		(fp_line
			(start -0.674878 1.100074)
			(end -0.674878 -1.100074)
			(stroke
				(width 0.1)
				(type default)
			)
			(layer "F.Fab")
		)
		(fp_line
			(start 0.674878 -1.100074)
			(end 0.674878 1.100074)
			(stroke
				(width 0.1)
				(type default)
			)
			(layer "F.Fab")
		)
		(fp_line
			(start 0.674878 1.100074)
			(end -0.674878 1.100074)
			(stroke
				(width 0.1)
				(type default)
			)
			(layer "F.Fab")
		)
		(fp_poly
			(pts
				(xy -2.2352 -0.298958) (xy -2.2352 -1.001014) (xy -1.533144 -0.649986)
			)
			(stroke
				(width 0)
				(type default)
			)
			(fill yes)
			(layer "F.Fab")
		)
		(pad "1" smd rect
			(at -0.94996 -0.649986 90)
			(size 0.4318 0.508)
			(layers "F.Cu" "F.Mask" "F.Paste")
			(net "GND")
		)
		(pad "2" smd rect
			(at -0.94996 0 90)
			(size 0.4318 0.508)
			(layers "F.Cu" "F.Mask" "F.Paste")
			(net "HPDB_HSC_PWRGD")
		)
		(pad "3" smd rect
			(at -0.94996 0.649986 90)
			(size 0.4318 0.508)
			(layers "F.Cu" "F.Mask" "F.Paste")
			(net "HPDB_HSC_PWRGD_ISO")
		)
		(pad "4" smd rect
			(at 0.94996 0.649986 90)
			(size 0.4318 0.508)
			(layers "F.Cu" "F.Mask" "F.Paste")
			(net "GND")
		)
		(pad "5" smd rect
			(at 0.94996 0 90)
			(size 0.4318 0.508)
			(layers "F.Cu" "F.Mask" "F.Paste")
			(net "HPDB_HSC_PWRGD_N")
		)
		(pad "6" smd rect
			(at 0.94996 -0.649986 90)
			(size 0.4318 0.508)
			(layers "F.Cu" "F.Mask" "F.Paste")
			(net "HPDB_HSC_PWRGD_N")
		)
	)
	(footprint ""
		(layer "F.Cu")
		(at 420.66972 -132.21716 180)
		(property "Reference" "PC2362"
			(at 0 0 180)
			(layer "F.SilkS")
			(hide yes)
			(effects
				(font
					(size 1.27 1.27)
				)
			)
		)
		(property "Value" ""
			(at 0 0 180)
			(layer "F.Fab")
			(effects
				(font
					(size 1.27 1.27)
				)
			)
		)
		(duplicate_pad_numbers_are_jumpers no)
		(fp_line
			(start 0.7874 0.4064)
			(end -0.7874 0.4064)
			(stroke
				(width 0.1524)
				(type default)
			)
			(layer "F.SilkS")
		)
		(fp_line
			(start 0.7874 -0.4064)
			(end 0.7874 0.4064)
			(stroke
				(width 0.1524)
				(type default)
			)
			(layer "F.SilkS")
		)
		(fp_line
			(start -0.7874 0.4064)
			(end -0.7874 -0.4064)
			(stroke
				(width 0.1524)
				(type default)
			)
			(layer "F.SilkS")
		)
		(fp_line
			(start -0.7874 -0.4064)
			(end 0.7874 -0.4064)
			(stroke
				(width 0.1524)
				(type default)
			)
			(layer "F.SilkS")
		)
		(fp_line
			(start 0.67945 0.3048)
			(end 0.120396 0.3048)
			(stroke
				(width 0.1)
				(type default)
			)
			(layer "F.Fab")
		)
		(fp_line
			(start 0.67945 -0.3048)
			(end 0.67945 0.3048)
			(stroke
				(width 0.1)
				(type default)
			)
			(layer "F.Fab")
		)
		(fp_line
			(start 0.12065 -0.2794)
			(end 0.12065 -0.3048)
			(stroke
				(width 0.1)
				(type default)
			)
			(layer "F.Fab")
		)
		(fp_line
			(start 0.12065 -0.3048)
			(end 0.67945 -0.3048)
			(stroke
				(width 0.1)
				(type default)
			)
			(layer "F.Fab")
		)
		(fp_line
			(start 0.120396 0.3048)
			(end 0.120396 0.2794)
			(stroke
				(width 0.1)
				(type default)
			)
			(layer "F.Fab")
		)
		(fp_line
			(start 0.120396 0.2794)
			(end -0.12065 0.2794)
			(stroke
				(width 0.1)
				(type default)
			)
			(layer "F.Fab")
		)
		(fp_line
			(start -0.12065 0.3048)
			(end -0.67945 0.3048)
			(stroke
				(width 0.1)
				(type default)
			)
			(layer "F.Fab")
		)
		(fp_line
			(start -0.12065 0.2794)
			(end -0.12065 0.3048)
			(stroke
				(width 0.1)
				(type default)
			)
			(layer "F.Fab")
		)
		(fp_line
			(start -0.12065 -0.2794)
			(end 0.12065 -0.2794)
			(stroke
				(width 0.1)
				(type default)
			)
			(layer "F.Fab")
		)
		(fp_line
			(start -0.12065 -0.305054)
			(end -0.12065 -0.2794)
			(stroke
				(width 0.1)
				(type default)
			)
			(layer "F.Fab")
		)
		(fp_line
			(start -0.67945 0.3048)
			(end -0.67945 -0.305054)
			(stroke
				(width 0.1)
				(type default)
			)
			(layer "F.Fab")
		)
		(fp_line
			(start -0.67945 -0.305054)
			(end -0.12065 -0.305054)
			(stroke
				(width 0.1)
				(type default)
			)
			(layer "F.Fab")
		)
		(pad "1" smd circle
			(at -0.40005 0 180)
			(size 0 0)
			(layers "F.Cu" "F.Mask" "F.Paste")
			(net "PVCCINFAON_CPU0_VCC")
		)
		(pad "2" smd circle
			(at 0.40005 0 180)
			(size 0 0)
			(layers "F.Cu" "F.Mask" "F.Paste")
			(net "GND")
		)
	)
	(footprint ""
		(layer "F.Cu")
		(at 420.453312 -366.658144)
		(property "Reference" "PC720_P0_1"
			(at 0 0 0)
			(layer "F.SilkS")
			(hide yes)
			(effects
				(font
					(size 1.27 1.27)
				)
			)
		)
		(property "Value" ""
			(at 0 0 0)
			(layer "F.Fab")
			(effects
				(font
					(size 1.27 1.27)
				)
			)
		)
		(duplicate_pad_numbers_are_jumpers no)
		(fp_line
			(start -1.524 -0.762)
			(end 1.524 -0.762)
			(stroke
				(width 0.1524)
				(type default)
			)
			(layer "F.SilkS")
		)
		(fp_line
			(start -1.524 0.762)
			(end -1.524 -0.762)
			(stroke
				(width 0.1524)
				(type default)
			)
			(layer "F.SilkS")
		)
		(fp_line
			(start 1.524 -0.762)
			(end 1.524 0.762)
			(stroke
				(width 0.1524)
				(type default)
			)
			(layer "F.SilkS")
		)
		(fp_line
			(start 1.524 0.762)
			(end -1.524 0.762)
			(stroke
				(width 0.1524)
				(type default)
			)
			(layer "F.SilkS")
		)
		(fp_line
			(start -1.1049 -0.724916)
			(end -1.1049 0.724916)
			(stroke
				(width 0.1)
				(type default)
			)
			(layer "F.Fab")
		)
		(fp_line
			(start -1.1049 0.724916)
			(end 1.1049 0.724916)
			(stroke
				(width 0.1)
				(type default)
			)
			(layer "F.Fab")
		)
		(fp_line
			(start 1.1049 -0.724916)
			(end -1.1049 -0.724916)
			(stroke
				(width 0.1)
				(type default)
			)
			(layer "F.Fab")
		)
		(fp_line
			(start 1.1049 0.724916)
			(end 1.1049 -0.724916)
			(stroke
				(width 0.1)
				(type default)
			)
			(layer "F.Fab")
		)
		(pad "1" smd rect
			(at -0.889 0 180)
			(size 1.016 1.27)
			(layers "F.Cu" "F.Mask" "F.Paste")
			(net "SW_P12V_PVCCFA_EHV_FIVRA_CPU0_R")
		)
		(pad "2" smd rect
			(at 0.889 0 180)
			(size 1.016 1.27)
			(layers "F.Cu" "F.Mask" "F.Paste")
			(net "GND")
		)
	)
)
